FILE_TYPE = CONNECTIVITY;
{Allegro Design Entry HDL 16.6-p007 (v16-6-112F) 10/10/2012}
"PAGE_NUMBER" = 36;
0"NC";
1"PVCCMCP_CPU0\g";
2"PVCCMCP_CPU0\g";
3"PVCCMCP_CPU0\g";
4"PVCCIOMCP_CPU0\g";
5"TP_CPU0_RSVD_144";
6"TP_CPU0_RSVD_150";
7"CLK_100M_CPU0_RC_REFCLK1_DP";
8"TP_CPU0_RSVD_154";
9"TP_CPU0_RSVD_149";
10"TP_CPU0_RSVD_148";
11"TP_CPU0_RSVD_147";
12"TP_CPU0_RSVD_146";
13"TP_CPU0_RSVD_145";
14"TP_CPU0_RSVD_152";
15"TP_CPU0_RSVD_151";
16"TP_CPU0_RSVD_124";
17"TP_CPU0_RSVD_82";
18"TP_CPU0_RSVD_113";
19"TP_CPU0_RSVD_155";
20"TP_CPU0_RSVD_156";
21"TP_CPU0_RSVD_157";
22"TP_CPU0_RSVD_158";
23"TP_CPU0_RSVD_159";
24"TP_CPU0_RSVD_160";
25"TP_CPU0_RSVD_161";
26"TP_CPU0_RSVD_162";
27"TP_CPU0_RSVD_163";
28"TP_CPU0_RSVD_164";
29"TP_CPU0_RSVD_166";
30"TP_CPU0_RSVD_167";
31"TP_CPU0_RSVD_168";
32"TP_CPU0_RSVD_169";
33"TP_CPU0_RSVD_170";
34"TP_CPU0_RSVD_171";
35"CLK_100M_CPU0_RC_REFCLK1_DN";
36"TP_CPU0_RSVD_255";
37"TP_CPU0_RSVD_94";
38"TP_CPU0_RSVD_95";
39"TP_CPU0_RSVD_97";
40"TP_CPU0_RSVD_99";
41"TP_CPU0_RSVD_100";
42"TP_CPU0_RSVD_101";
43"TP_CPU0_RSVD_105";
44"TP_CPU0_RSVD_106";
45"TP_CPU0_RSVD_108";
46"TP_CPU0_RSVD_111";
47"TP_CPU0_RSVD_114";
48"TP_CPU0_RSVD_117";
49"TP_CPU0_RSVD_119";
50"TP_CPU0_RSVD_121";
51"TP_CPU0_RSVD_123";
52"TP_CPU0_TEST_9";
53"TP_CPU0_TEST_8";
54"TP_CPU0_TEST_7";
55"TP_CPU0_TEST_6";
56"TP_CPU0_TEST_10";
57"TP_CPU0_RSVD_85";
58"TP_CPU0_RSVD_90";
59"TP_CPU0_RSVD_91";
%"VCC_CORE"
"1","(-4500,3800)","0","mstr_symbols","I12";
;
HDL_POWER"PVCCMCP_CPU0"
CDS_LIB"mstr_symbols";
"A"1;
%"VCC_CORE"
"1","(-925,2700)","0","mstr_symbols","I13";
;
HDL_POWER"PVCCMCP_CPU0"
CDS_LIB"mstr_symbols";
"A"2;
%"VCC_CORE"
"1","(-7850,2350)","0","mstr_symbols","I14";
;
HDL_POWER"PVCCMCP_CPU0"
CDS_LIB"mstr_symbols";
"A"3;
%"SKX_EXT_B"
"16","(-6075,2550)","0","chpset_lib","I15";
;
CDS_SEC"16"
LOCATION"U5D1"
PART_NUMBER"TBD"
MATERIAL"IC"
PACK_TYPE"BGA1"
SEC_TYPE"BGA1"
CDS_LIB"chpset_lib"
SEC"16"
CDS_LOCATION"U5D1"
ROOM"CPU0";
"RSVD<92>"
$PN"CH23"1;
"RSVD<93>"
$PN"CH21"1;
"RSVD<94>"
$PN"CG82"37;
"RSVD<95>"
$PN"CG78"38;
"RSVD<96>"
$PN"CG26"1;
"RSVD<97>"
$PN"CG24"39;
"RSVD<98>"
$PN"CG20"1;
"RSVD<99>"
$PN"CG10"40;
"RSVD<100>"
$PN"CF81"41;
"RSVD<101>"
$PN"CF79"42;
"RSVD<102>"
$PN"CF23"1;
"RSVD<103>"
$PN"CF21"1;
"RSVD<104>"
$PN"CF19"1;
"RSVD<105>"
$PN"CE80"43;
"RSVD<106>"
$PN"CE78"44;
"RSVD<107>"
$PN"CE22"1;
"RSVD<108>"
$PN"CD25"45;
"RSVD<109>"
$PN"CD21"1;
"RSVD<110>"
$PN"CD19"1;
"RSVD<111>"
$PN"CC6"46;
"RSVD<112>"
$PN"CC20"1;
"RSVD<113>"
$PN"CB5"18;
"RSVD<114>"
$PN"CB25"47;
"RSVD<115>"
$PN"CB21"1;
"RSVD<116>"
$PN"CB19"1;
"RSVD<117>"
$PN"CA24"48;
"RSVD<118>"
$PN"CA22"1;
"RSVD<119>"
$PN"BY25"49;
"RSVD<120>"
$PN"BY19"1;
"RSVD<121>"
$PN"BW22"50;
"RSVD<122>"
$PN"BW20"1;
"RSVD<123>"
$PN"BW10"51;
"RSVD<124>"
$PN"BV23"16;
"RSVD<125>"
$PN"BV21"1;
"RSVD<126>"
$PN"BV19"1;
"RSVD<127>"
$PN"BU22"3;
"RSVD<128>"
$PN"BU20"3;
"RSVD<129>"
$PN"BU18"4;
"RSVD<130>"
$PN"BR24"3;
"RSVD<131>"
$PN"BR22"3;
"RSVD<132>"
$PN"BP21"3;
"RSVD<133>"
$PN"BP17"4;
"RSVD<134>"
$PN"BN18"4;
"RSVD<135>"
$PN"BM19"3;
"RSVD<136>"
$PN"BM17"4;
"RSVD<137>"
$PN"BL20"3;
"RSVD<138>"
$PN"BL18"4;
"RSVD<139>"
$PN"BK17"3;
"RSVD<140>"
$PN"BJ20"3;
"RSVD<141>"
$PN"BJ18"3;
"RSVD<142>"
$PN"BJ16"3;
"RSVD<143>"
$PN"BH19"3;
"RSVD<144>"
$PN"BG20"5;
"RSVD<145>"
$PN"BG18"13;
"RSVD<146>"
$PN"BF21"12;
"RSVD<147>"
$PN"BE22"11;
"RSVD<148>"
$PN"BE20"10;
"RSVD<149>"
$PN"BE18"9;
"RSVD<150>"
$PN"BD69"6;
"RSVD<151>"
$PN"BD67"15;
"RSVD<152>"
$PN"BD65"14;
"RSVD<153>"
$PN"BD25"7;
"RSVD<154>"
$PN"BD19"8;
"RSVD<155>"
$PN"BD17"19;
"RSVD<156>"
$PN"BC68"20;
"RSVD<157>"
$PN"BC66"21;
"RSVD<158>"
$PN"BC64"22;
"RSVD<159>"
$PN"BC22"23;
"RSVD<160>"
$PN"BC20"24;
"RSVD<161>"
$PN"BC18"25;
"RSVD<162>"
$PN"BC14"26;
"RSVD<163>"
$PN"BB67"27;
"RSVD<164>"
$PN"BB65"28;
"RSVD<165>"
$PN"BB25"35;
"RSVD<166>"
$PN"BB21"29;
"RSVD<167>"
$PN"BB17"30;
"RSVD<168>"
$PN"BB15"31;
"RSVD<169>"
$PN"BB13"32;
"RSVD<170>"
$PN"BA82"33;
"RSVD<171>"
$PN"BA78"34;
"RSVD<255>"
$PN"AY83"36;
%"SKX_EXT_B"
"17","(-2550,2525)","0","chpset_lib","I16";
;
CDS_SEC"17"
LOCATION"U5D1"
PART_NUMBER"TBD"
MATERIAL"IC"
PACK_TYPE"BGA1"
SEC_TYPE"BGA1"
CDS_LIB"chpset_lib"
SEC"17"
CDS_LOCATION"U5D1"
ROOM"CPU0";
"TEST_9"
$PN"AW20"52;
"TEST_8"
$PN"AW16"53;
"TEST_7"
$PN"AU18"54;
"TEST_6"
$PN"AR16"55;
"TEST_10"
$PN"AW22"56;
"RSVD<81>"
$PN"CL24"2;
"RSVD<82>"
$PN"CK77"17;
"RSVD<83>"
$PN"CK25"2;
"RSVD<84>"
$PN"CK23"2;
"RSVD<85>"
$PN"CK19"57;
"RSVD<86>"
$PN"CJ26"2;
"RSVD<87>"
$PN"CJ24"2;
"RSVD<88>"
$PN"CJ22"2;
"RSVD<89>"
$PN"CJ20"2;
"RSVD<90>"
$PN"CH77"58;
"RSVD<91>"
$PN"CH25"59;
%"VCC_CORE"
"1","(-7850,2100)","0","mstr_symbols","I17";
;
HDL_POWER"PVCCIOMCP_CPU0"
CDS_LIB"mstr_symbols";
"A"4;
END.
